(kicad_pcb
	(version 20260206)
	(generator "pcbnew")
	(generator_version "10.0")
	(general
		(thickness 1.6)
		(legacy_teardrops no)
	)
	(paper "A4")
	(title_block
		(title "01162023_DA0F0TEBIF0_F0T_Expander_BD_F_brd_V02_OCP.brd")
		(comment 1 "Grand Teton / footprints 464-470 of 9728")
	)
	(layers
		(0 "F.Cu" signal "TOP")
		(4 "In1.Cu" signal "GND")
		(6 "In2.Cu" signal "VCC")
		(8 "In3.Cu" signal "VCC1")
		(10 "In4.Cu" signal "GND1")
		(12 "In5.Cu" signal "IN1")
		(14 "In6.Cu" signal "GND2")
		(16 "In7.Cu" signal "IN2")
		(18 "In8.Cu" signal "GND3")
		(20 "In9.Cu" signal "IN3")
		(22 "In10.Cu" signal "GND4")
		(24 "In11.Cu" signal "IN4")
		(26 "In12.Cu" signal "GND5")
		(28 "In13.Cu" signal "IN5")
		(30 "In14.Cu" signal "GND6")
		(32 "In15.Cu" signal "IN6")
		(34 "In16.Cu" signal "GND7")
		(2 "B.Cu" signal "BOTTOM")
		(9 "F.Adhes" user "F.Adhesive")
		(11 "B.Adhes" user "B.Adhesive")
		(13 "F.Paste" user "Package Geometry/Pastemask Top")
		(15 "B.Paste" user "Package Geometry/Pastemask Bottom")
		(5 "F.SilkS" user "Ref Des/Silkscreen Top")
		(7 "B.SilkS" user "Ref Des/Silkscreen Bottom")
		(1 "F.Mask" user "Board Geometry/Soldermask Top")
		(3 "B.Mask" user "Board Geometry/Soldermask Bottom")
		(17 "Dwgs.User" user "User.Drawings")
		(19 "Cmts.User" user "User.Comments")
		(21 "Eco1.User" user "User.Eco1")
		(23 "Eco2.User" user "User.Eco2")
		(25 "Edge.Cuts" user "Board Geometry/Outline")
		(27 "Margin" user)
		(31 "F.CrtYd" user "Package Geometry/Place Bound Top")
		(29 "B.CrtYd" user "Package Geometry/Place Bound Bottom")
		(35 "F.Fab" user "Ref Des/Assembly Top")
		(33 "B.Fab" user "Ref Des/Assembly Bottom")
	)
	(footprint ""
		(layer "F.Cu")
		(at 256.681986 -38.041072 180)
		(property "Reference" "R6085"
			(at 0 0 180)
			(layer "F.SilkS")
			(hide yes)
			(effects
				(font
					(size 1.27 1.27)
				)
			)
		)
		(property "Value" ""
			(at 0 0 180)
			(layer "F.Fab")
			(effects
				(font
					(size 1.27 1.27)
				)
			)
		)
		(duplicate_pad_numbers_are_jumpers no)
		(fp_line
			(start 0.7874 0.4064)
			(end -0.7874 0.4064)
			(stroke
				(width 0.1524)
				(type default)
			)
			(layer "F.SilkS")
		)
		(fp_line
			(start 0.7874 -0.4064)
			(end 0.7874 0.4064)
			(stroke
				(width 0.1524)
				(type default)
			)
			(layer "F.SilkS")
		)
		(fp_line
			(start -0.7874 0.4064)
			(end -0.7874 -0.4064)
			(stroke
				(width 0.1524)
				(type default)
			)
			(layer "F.SilkS")
		)
		(fp_line
			(start -0.7874 -0.4064)
			(end 0.7874 -0.4064)
			(stroke
				(width 0.1524)
				(type default)
			)
			(layer "F.SilkS")
		)
		(fp_line
			(start 0.67945 0.3048)
			(end 0.120396 0.3048)
			(stroke
				(width 0.1)
				(type default)
			)
			(layer "F.Fab")
		)
		(fp_line
			(start 0.67945 -0.3048)
			(end 0.67945 0.3048)
			(stroke
				(width 0.1)
				(type default)
			)
			(layer "F.Fab")
		)
		(fp_line
			(start 0.12065 -0.2794)
			(end 0.12065 -0.3048)
			(stroke
				(width 0.1)
				(type default)
			)
			(layer "F.Fab")
		)
		(fp_line
			(start 0.12065 -0.3048)
			(end 0.67945 -0.3048)
			(stroke
				(width 0.1)
				(type default)
			)
			(layer "F.Fab")
		)
		(fp_line
			(start 0.120396 0.3048)
			(end 0.120396 0.2794)
			(stroke
				(width 0.1)
				(type default)
			)
			(layer "F.Fab")
		)
		(fp_line
			(start 0.120396 0.2794)
			(end -0.12065 0.2794)
			(stroke
				(width 0.1)
				(type default)
			)
			(layer "F.Fab")
		)
		(fp_line
			(start -0.12065 0.3048)
			(end -0.67945 0.3048)
			(stroke
				(width 0.1)
				(type default)
			)
			(layer "F.Fab")
		)
		(fp_line
			(start -0.12065 0.2794)
			(end -0.12065 0.3048)
			(stroke
				(width 0.1)
				(type default)
			)
			(layer "F.Fab")
		)
		(fp_line
			(start -0.12065 -0.2794)
			(end 0.12065 -0.2794)
			(stroke
				(width 0.1)
				(type default)
			)
			(layer "F.Fab")
		)
		(fp_line
			(start -0.12065 -0.305054)
			(end -0.12065 -0.2794)
			(stroke
				(width 0.1)
				(type default)
			)
			(layer "F.Fab")
		)
		(fp_line
			(start -0.67945 0.3048)
			(end -0.67945 -0.305054)
			(stroke
				(width 0.1)
				(type default)
			)
			(layer "F.Fab")
		)
		(fp_line
			(start -0.67945 -0.305054)
			(end -0.12065 -0.305054)
			(stroke
				(width 0.1)
				(type default)
			)
			(layer "F.Fab")
		)
		(pad "1" smd circle
			(at -0.40005 0 180)
			(size 0 0)
			(layers "F.Cu" "F.Mask" "F.Paste")
			(net "P5V_AUX")
		)
		(pad "2" smd circle
			(at 0.40005 0 180)
			(size 0 0)
			(layers "F.Cu" "F.Mask" "F.Paste")
			(net "P3V3_SSD9_PG_G2")
		)
	)
	(footprint ""
		(layer "F.Cu")
		(at 92.436442 -343.952322 90)
		(property "Reference" "C157"
			(at 0 0 90)
			(layer "F.SilkS")
			(hide yes)
			(effects
				(font
					(size 1.27 1.27)
				)
			)
		)
		(property "Value" ""
			(at 0 0 90)
			(layer "F.Fab")
			(effects
				(font
					(size 1.27 1.27)
				)
			)
		)
		(duplicate_pad_numbers_are_jumpers no)
		(fp_line
			(start 0.299974 -0.150114)
			(end 0.299974 0.150114)
			(stroke
				(width 0.1)
				(type default)
			)
			(layer "F.Fab")
		)
		(fp_line
			(start -0.299974 -0.150114)
			(end 0.299974 -0.150114)
			(stroke
				(width 0.1)
				(type default)
			)
			(layer "F.Fab")
		)
		(fp_line
			(start 0.299974 0.150114)
			(end -0.299974 0.150114)
			(stroke
				(width 0.1)
				(type default)
			)
			(layer "F.Fab")
		)
		(fp_line
			(start -0.299974 0.150114)
			(end -0.299974 -0.150114)
			(stroke
				(width 0.1)
				(type default)
			)
			(layer "F.Fab")
		)
		(pad "1" smd rect
			(at -0.2667 0 90)
			(size 0.3048 0.381)
			(layers "F.Cu" "F.Mask" "F.Paste")
			(net "P5E_PEX0_STN6_TX_DP<97>")
		)
		(pad "2" smd rect
			(at 0.2667 0 90)
			(size 0.3048 0.381)
			(layers "F.Cu" "F.Mask" "F.Paste")
			(net "P5E_PEX0_STN6_TX_C_DP<97>")
		)
	)
	(footprint ""
		(layer "F.Cu")
		(at 135.754872 -22.867366 90)
		(property "Reference" "C3902"
			(at 0 0 90)
			(layer "F.SilkS")
			(hide yes)
			(effects
				(font
					(size 1.27 1.27)
				)
			)
		)
		(property "Value" ""
			(at 0 0 90)
			(layer "F.Fab")
			(effects
				(font
					(size 1.27 1.27)
				)
			)
		)
		(duplicate_pad_numbers_are_jumpers no)
		(fp_line
			(start 0.7874 -0.4064)
			(end 0.7874 0.4064)
			(stroke
				(width 0.1524)
				(type default)
			)
			(layer "F.SilkS")
		)
		(fp_line
			(start -0.7874 -0.4064)
			(end 0.7874 -0.4064)
			(stroke
				(width 0.1524)
				(type default)
			)
			(layer "F.SilkS")
		)
		(fp_line
			(start 0.7874 0.4064)
			(end -0.7874 0.4064)
			(stroke
				(width 0.1524)
				(type default)
			)
			(layer "F.SilkS")
		)
		(fp_line
			(start -0.7874 0.4064)
			(end -0.7874 -0.4064)
			(stroke
				(width 0.1524)
				(type default)
			)
			(layer "F.SilkS")
		)
		(fp_line
			(start -0.12065 -0.305054)
			(end -0.12065 -0.2794)
			(stroke
				(width 0.1)
				(type default)
			)
			(layer "F.Fab")
		)
		(fp_line
			(start -0.67945 -0.305054)
			(end -0.12065 -0.305054)
			(stroke
				(width 0.1)
				(type default)
			)
			(layer "F.Fab")
		)
		(fp_line
			(start 0.67945 -0.3048)
			(end 0.67945 0.3048)
			(stroke
				(width 0.1)
				(type default)
			)
			(layer "F.Fab")
		)
		(fp_line
			(start 0.12065 -0.3048)
			(end 0.67945 -0.3048)
			(stroke
				(width 0.1)
				(type default)
			)
			(layer "F.Fab")
		)
		(fp_line
			(start 0.12065 -0.2794)
			(end 0.12065 -0.3048)
			(stroke
				(width 0.1)
				(type default)
			)
			(layer "F.Fab")
		)
		(fp_line
			(start -0.12065 -0.2794)
			(end 0.12065 -0.2794)
			(stroke
				(width 0.1)
				(type default)
			)
			(layer "F.Fab")
		)
		(fp_line
			(start 0.120396 0.2794)
			(end -0.12065 0.2794)
			(stroke
				(width 0.1)
				(type default)
			)
			(layer "F.Fab")
		)
		(fp_line
			(start -0.12065 0.2794)
			(end -0.12065 0.3048)
			(stroke
				(width 0.1)
				(type default)
			)
			(layer "F.Fab")
		)
		(fp_line
			(start 0.67945 0.3048)
			(end 0.120396 0.3048)
			(stroke
				(width 0.1)
				(type default)
			)
			(layer "F.Fab")
		)
		(fp_line
			(start 0.120396 0.3048)
			(end 0.120396 0.2794)
			(stroke
				(width 0.1)
				(type default)
			)
			(layer "F.Fab")
		)
		(fp_line
			(start -0.12065 0.3048)
			(end -0.67945 0.3048)
			(stroke
				(width 0.1)
				(type default)
			)
			(layer "F.Fab")
		)
		(fp_line
			(start -0.67945 0.3048)
			(end -0.67945 -0.305054)
			(stroke
				(width 0.1)
				(type default)
			)
			(layer "F.Fab")
		)
		(pad "1" smd circle
			(at -0.40005 0 90)
			(size 0 0)
			(layers "F.Cu" "F.Mask" "F.Paste")
			(net "P12V_SSD4")
		)
		(pad "2" smd circle
			(at 0.40005 0 90)
			(size 0 0)
			(layers "F.Cu" "F.Mask" "F.Paste")
			(net "GND")
		)
	)
	(footprint ""
		(layer "F.Cu")
		(at 63.6778 -117.566186)
		(property "Reference" "R92"
			(at 0 0 0)
			(layer "F.SilkS")
			(hide yes)
			(effects
				(font
					(size 1.27 1.27)
				)
			)
		)
		(property "Value" ""
			(at 0 0 0)
			(layer "F.Fab")
			(effects
				(font
					(size 1.27 1.27)
				)
			)
		)
		(duplicate_pad_numbers_are_jumpers no)
		(fp_line
			(start -0.7874 -0.4064)
			(end 0.7874 -0.4064)
			(stroke
				(width 0.1524)
				(type default)
			)
			(layer "F.SilkS")
		)
		(fp_line
			(start -0.7874 0.4064)
			(end -0.7874 -0.4064)
			(stroke
				(width 0.1524)
				(type default)
			)
			(layer "F.SilkS")
		)
		(fp_line
			(start 0.7874 -0.4064)
			(end 0.7874 0.4064)
			(stroke
				(width 0.1524)
				(type default)
			)
			(layer "F.SilkS")
		)
		(fp_line
			(start 0.7874 0.4064)
			(end -0.7874 0.4064)
			(stroke
				(width 0.1524)
				(type default)
			)
			(layer "F.SilkS")
		)
		(fp_line
			(start -0.67945 -0.305054)
			(end -0.12065 -0.305054)
			(stroke
				(width 0.1)
				(type default)
			)
			(layer "F.Fab")
		)
		(fp_line
			(start -0.67945 0.3048)
			(end -0.67945 -0.305054)
			(stroke
				(width 0.1)
				(type default)
			)
			(layer "F.Fab")
		)
		(fp_line
			(start -0.12065 -0.305054)
			(end -0.12065 -0.2794)
			(stroke
				(width 0.1)
				(type default)
			)
			(layer "F.Fab")
		)
		(fp_line
			(start -0.12065 -0.2794)
			(end 0.12065 -0.2794)
			(stroke
				(width 0.1)
				(type default)
			)
			(layer "F.Fab")
		)
		(fp_line
			(start -0.12065 0.2794)
			(end -0.12065 0.3048)
			(stroke
				(width 0.1)
				(type default)
			)
			(layer "F.Fab")
		)
		(fp_line
			(start -0.12065 0.3048)
			(end -0.67945 0.3048)
			(stroke
				(width 0.1)
				(type default)
			)
			(layer "F.Fab")
		)
		(fp_line
			(start 0.120396 0.2794)
			(end -0.12065 0.2794)
			(stroke
				(width 0.1)
				(type default)
			)
			(layer "F.Fab")
		)
		(fp_line
			(start 0.120396 0.3048)
			(end 0.120396 0.2794)
			(stroke
				(width 0.1)
				(type default)
			)
			(layer "F.Fab")
		)
		(fp_line
			(start 0.12065 -0.3048)
			(end 0.67945 -0.3048)
			(stroke
				(width 0.1)
				(type default)
			)
			(layer "F.Fab")
		)
		(fp_line
			(start 0.12065 -0.2794)
			(end 0.12065 -0.3048)
			(stroke
				(width 0.1)
				(type default)
			)
			(layer "F.Fab")
		)
		(fp_line
			(start 0.67945 -0.3048)
			(end 0.67945 0.3048)
			(stroke
				(width 0.1)
				(type default)
			)
			(layer "F.Fab")
		)
		(fp_line
			(start 0.67945 0.3048)
			(end 0.120396 0.3048)
			(stroke
				(width 0.1)
				(type default)
			)
			(layer "F.Fab")
		)
		(pad "1" smd circle
			(at -0.40005 0)
			(size 0 0)
			(layers "F.Cu" "F.Mask" "F.Paste")
			(net "PRSNT_NIC1_N")
		)
		(pad "2" smd circle
			(at 0.40005 0)
			(size 0 0)
			(layers "F.Cu" "F.Mask" "F.Paste")
			(net "PRSNTB2_NIC1_N")
		)
	)
	(footprint ""
		(layer "F.Cu")
		(at 211.558886 -231.150922 90)
		(property "Reference" "R1548"
			(at 0 0 90)
			(layer "F.SilkS")
			(hide yes)
			(effects
				(font
					(size 1.27 1.27)
				)
			)
		)
		(property "Value" ""
			(at 0 0 90)
			(layer "F.Fab")
			(effects
				(font
					(size 1.27 1.27)
				)
			)
		)
		(duplicate_pad_numbers_are_jumpers no)
		(fp_line
			(start 0.7874 -0.4064)
			(end 0.7874 0.4064)
			(stroke
				(width 0.1524)
				(type default)
			)
			(layer "F.SilkS")
		)
		(fp_line
			(start -0.7874 -0.4064)
			(end 0.7874 -0.4064)
			(stroke
				(width 0.1524)
				(type default)
			)
			(layer "F.SilkS")
		)
		(fp_line
			(start 0.7874 0.4064)
			(end -0.7874 0.4064)
			(stroke
				(width 0.1524)
				(type default)
			)
			(layer "F.SilkS")
		)
		(fp_line
			(start -0.7874 0.4064)
			(end -0.7874 -0.4064)
			(stroke
				(width 0.1524)
				(type default)
			)
			(layer "F.SilkS")
		)
		(fp_line
			(start -0.12065 -0.305054)
			(end -0.12065 -0.2794)
			(stroke
				(width 0.1)
				(type default)
			)
			(layer "F.Fab")
		)
		(fp_line
			(start -0.67945 -0.305054)
			(end -0.12065 -0.305054)
			(stroke
				(width 0.1)
				(type default)
			)
			(layer "F.Fab")
		)
		(fp_line
			(start 0.67945 -0.3048)
			(end 0.67945 0.3048)
			(stroke
				(width 0.1)
				(type default)
			)
			(layer "F.Fab")
		)
		(fp_line
			(start 0.12065 -0.3048)
			(end 0.67945 -0.3048)
			(stroke
				(width 0.1)
				(type default)
			)
			(layer "F.Fab")
		)
		(fp_line
			(start 0.12065 -0.2794)
			(end 0.12065 -0.3048)
			(stroke
				(width 0.1)
				(type default)
			)
			(layer "F.Fab")
		)
		(fp_line
			(start -0.12065 -0.2794)
			(end 0.12065 -0.2794)
			(stroke
				(width 0.1)
				(type default)
			)
			(layer "F.Fab")
		)
		(fp_line
			(start 0.120396 0.2794)
			(end -0.12065 0.2794)
			(stroke
				(width 0.1)
				(type default)
			)
			(layer "F.Fab")
		)
		(fp_line
			(start -0.12065 0.2794)
			(end -0.12065 0.3048)
			(stroke
				(width 0.1)
				(type default)
			)
			(layer "F.Fab")
		)
		(fp_line
			(start 0.67945 0.3048)
			(end 0.120396 0.3048)
			(stroke
				(width 0.1)
				(type default)
			)
			(layer "F.Fab")
		)
		(fp_line
			(start 0.120396 0.3048)
			(end 0.120396 0.2794)
			(stroke
				(width 0.1)
				(type default)
			)
			(layer "F.Fab")
		)
		(fp_line
			(start -0.12065 0.3048)
			(end -0.67945 0.3048)
			(stroke
				(width 0.1)
				(type default)
			)
			(layer "F.Fab")
		)
		(fp_line
			(start -0.67945 0.3048)
			(end -0.67945 -0.305054)
			(stroke
				(width 0.1)
				(type default)
			)
			(layer "F.Fab")
		)
		(pad "1" smd circle
			(at -0.40005 0 90)
			(size 0 0)
			(layers "F.Cu" "F.Mask" "F.Paste")
			(net "SMB_PEX_LS_R_SDA")
		)
		(pad "2" smd circle
			(at 0.40005 0 90)
			(size 0 0)
			(layers "F.Cu" "F.Mask" "F.Paste")
			(net "SMB_PEX2_SDA")
		)
	)
	(footprint ""
		(layer "F.Cu")
		(at 233.800904 -254.18542 -90)
		(property "Reference" "C4355"
			(at 0 0 270)
			(layer "F.SilkS")
			(hide yes)
			(effects
				(font
					(size 1.27 1.27)
				)
			)
		)
		(property "Value" ""
			(at 0 0 270)
			(layer "F.Fab")
			(effects
				(font
					(size 1.27 1.27)
				)
			)
		)
		(duplicate_pad_numbers_are_jumpers no)
		(fp_line
			(start -1.2954 0.5842)
			(end -1.2954 -0.5842)
			(stroke
				(width 0.1524)
				(type default)
			)
			(layer "F.SilkS")
		)
		(fp_line
			(start 1.2954 0.5842)
			(end -1.2954 0.5842)
			(stroke
				(width 0.1524)
				(type default)
			)
			(layer "F.SilkS")
		)
		(fp_line
			(start -1.2954 -0.5842)
			(end 1.2954 -0.5842)
			(stroke
				(width 0.1524)
				(type default)
			)
			(layer "F.SilkS")
		)
		(fp_line
			(start 1.2954 -0.5842)
			(end 1.2954 0.5842)
			(stroke
				(width 0.1524)
				(type default)
			)
			(layer "F.SilkS")
		)
		(fp_line
			(start -0.8636 0.4572)
			(end -0.8636 0.4064)
			(stroke
				(width 0.1)
				(type default)
			)
			(layer "F.Fab")
		)
		(fp_line
			(start 0.8636 0.4572)
			(end -0.8636 0.4572)
			(stroke
				(width 0.1)
				(type default)
			)
			(layer "F.Fab")
		)
		(fp_line
			(start -1.1938 0.4064)
			(end -1.1938 -0.4064)
			(stroke
				(width 0.1)
				(type default)
			)
			(layer "F.Fab")
		)
		(fp_line
			(start -0.8636 0.4064)
			(end -1.1938 0.4064)
			(stroke
				(width 0.1)
				(type default)
			)
			(layer "F.Fab")
		)
		(fp_line
			(start 0.8636 0.4064)
			(end 0.8636 0.4572)
			(stroke
				(width 0.1)
				(type default)
			)
			(layer "F.Fab")
		)
		(fp_line
			(start 1.1938 0.4064)
			(end 0.8636 0.4064)
			(stroke
				(width 0.1)
				(type default)
			)
			(layer "F.Fab")
		)
		(fp_line
			(start -1.1938 -0.4064)
			(end -0.8636 -0.4064)
			(stroke
				(width 0.1)
				(type default)
			)
			(layer "F.Fab")
		)
		(fp_line
			(start -0.8636 -0.4064)
			(end -0.8636 -0.4572)
			(stroke
				(width 0.1)
				(type default)
			)
			(layer "F.Fab")
		)
		(fp_line
			(start 0.8636 -0.4064)
			(end 1.1938 -0.4064)
			(stroke
				(width 0.1)
				(type default)
			)
			(layer "F.Fab")
		)
		(fp_line
			(start 1.1938 -0.4064)
			(end 1.1938 0.4064)
			(stroke
				(width 0.1)
				(type default)
			)
			(layer "F.Fab")
		)
		(fp_line
			(start -0.8636 -0.4572)
			(end 0.8636 -0.4572)
			(stroke
				(width 0.1)
				(type default)
			)
			(layer "F.Fab")
		)
		(fp_line
			(start 0.8636 -0.4572)
			(end 0.8636 -0.4064)
			(stroke
				(width 0.1)
				(type default)
			)
			(layer "F.Fab")
		)
		(pad "1" smd rect
			(at -0.7366 0 180)
			(size 0.7112 0.8128)
			(layers "F.Cu" "F.Mask" "F.Paste")
			(net "P1V25_SERDES_VDDPLL_PEX2_C9")
		)
		(pad "2" smd rect
			(at 0.7366 0 180)
			(size 0.7112 0.8128)
			(layers "F.Cu" "F.Mask" "F.Paste")
			(net "GND")
		)
	)
	(footprint ""
		(layer "F.Cu")
		(at 135.626856 -170.599862 90)
		(property "Reference" "R1096"
			(at 0 0 90)
			(layer "F.SilkS")
			(hide yes)
			(effects
				(font
					(size 1.27 1.27)
				)
			)
		)
		(property "Value" ""
			(at 0 0 90)
			(layer "F.Fab")
			(effects
				(font
					(size 1.27 1.27)
				)
			)
		)
		(duplicate_pad_numbers_are_jumpers no)
		(fp_line
			(start -0.7874 -0.4064)
			(end 0.7874 -0.4064)
			(stroke
				(width 0.1524)
				(type default)
			)
			(layer "F.SilkS")
		)
		(fp_line
			(start -0.12065 -0.305054)
			(end -0.12065 -0.2794)
			(stroke
				(width 0.1)
				(type default)
			)
			(layer "F.Fab")
		)
		(fp_line
			(start -0.67945 -0.305054)
			(end -0.12065 -0.305054)
			(stroke
				(width 0.1)
				(type default)
			)
			(layer "F.Fab")
		)
		(fp_line
			(start 0.67945 -0.3048)
			(end 0.67945 0.3048)
			(stroke
				(width 0.1)
				(type default)
			)
			(layer "F.Fab")
		)
		(fp_line
			(start 0.12065 -0.3048)
			(end 0.67945 -0.3048)
			(stroke
				(width 0.1)
				(type default)
			)
			(layer "F.Fab")
		)
		(fp_line
			(start 0.12065 -0.2794)
			(end 0.12065 -0.3048)
			(stroke
				(width 0.1)
				(type default)
			)
			(layer "F.Fab")
		)
		(fp_line
			(start -0.12065 -0.2794)
			(end 0.12065 -0.2794)
			(stroke
				(width 0.1)
				(type default)
			)
			(layer "F.Fab")
		)
		(fp_line
			(start 0.120396 0.2794)
			(end -0.12065 0.2794)
			(stroke
				(width 0.1)
				(type default)
			)
			(layer "F.Fab")
		)
		(fp_line
			(start -0.12065 0.2794)
			(end -0.12065 0.3048)
			(stroke
				(width 0.1)
				(type default)
			)
			(layer "F.Fab")
		)
		(fp_line
			(start 0.67945 0.3048)
			(end 0.120396 0.3048)
			(stroke
				(width 0.1)
				(type default)
			)
			(layer "F.Fab")
		)
		(fp_line
			(start 0.120396 0.3048)
			(end 0.120396 0.2794)
			(stroke
				(width 0.1)
				(type default)
			)
			(layer "F.Fab")
		)
		(fp_line
			(start -0.12065 0.3048)
			(end -0.67945 0.3048)
			(stroke
				(width 0.1)
				(type default)
			)
			(layer "F.Fab")
		)
		(fp_line
			(start -0.67945 0.3048)
			(end -0.67945 -0.305054)
			(stroke
				(width 0.1)
				(type default)
			)
			(layer "F.Fab")
		)
		(pad "1" smd circle
			(at -0.40005 0 90)
			(size 0 0)
			(layers "F.Cu" "F.Mask" "F.Paste")
			(net "CLK_100M_DB2000QL_NIC1_R_DP")
		)
		(pad "2" smd circle
			(at 0.40005 0 90)
			(size 0 0)
			(layers "F.Cu" "F.Mask" "F.Paste")
			(net "CLK_100M_DB2000QL_NIC1_DP")
		)
	)
)
